(kicad_pcb
	(version 20241229)
	(generator "pcbnew")
	(generator_version "9.0")
	(general
		(thickness 1.61)
		(legacy_teardrops no)
	)
	(paper "A3")
	(title_block
		(title "SO-DIMM DDR5 Tester")
		(date "2025-11-26")
		(rev "1.3.0")
		(comment 9 "footprints 467-472 of 627")
	)
	(layers
		(0 "F.Cu" signal)
		(4 "In1.Cu" power)
		(6 "In2.Cu" mixed)
		(8 "In3.Cu" power)
		(10 "In4.Cu" mixed)
		(12 "In5.Cu" power)
		(14 "In6.Cu" mixed)
		(16 "In7.Cu" power)
		(18 "In8.Cu" power)
		(20 "In9.Cu" mixed)
		(22 "In10.Cu" power)
		(2 "B.Cu" signal)
		(9 "F.Adhes" user "F.Adhesive")
		(11 "B.Adhes" user "B.Adhesive")
		(13 "F.Paste" user)
		(15 "B.Paste" user)
		(5 "F.SilkS" user "F.Silkscreen")
		(7 "B.SilkS" user "B.Silkscreen")
		(1 "F.Mask" user)
		(3 "B.Mask" user)
		(17 "Dwgs.User" user "User.Drawings")
		(19 "Cmts.User" user "User.Comments")
		(21 "Eco1.User" user "User.Eco1")
		(23 "Eco2.User" user "User.Eco2")
		(25 "Edge.Cuts" user)
		(27 "Margin" user)
		(31 "F.CrtYd" user "F.Courtyard")
		(29 "B.CrtYd" user "B.Courtyard")
		(35 "F.Fab" user)
		(33 "B.Fab" user)
	)
	(footprint "antmicro-footprints:C_0402_1005Metric"
		(layer "B.Cu")
		(at 147.375001 170.8005 -90)
		(descr "Capacitor SMD 0402 (1005 Metric), square (rectangular) end terminal, IPC_7351 nominal, (Body size source: IPC-SM-782 page 76, https://www.pcb-3d.com/wordpress/wp-content/uploads/ipc-sm-782a_amendment_1_and_2.pdf)")
		(tags "capacitor 0402")
		(property "Reference" "C80"
			(at 0 1.17 90)
			(layer "B.SilkS")
			(hide yes)
			(effects
				(font
					(size 0.7 0.7)
					(thickness 0.15)
				)
				(justify left bottom mirror)
			)
		)
		(property "Value" "C_100n_0402"
			(at 0 -1.169 90)
			(layer "B.Fab")
			(effects
				(font
					(size 0.7 0.7)
					(thickness 0.15)
				)
				(justify left bottom mirror)
			)
		)
		(property "Datasheet" "https://www.murata.com/products/productdetail?partno=GRM155R61H104KE14%23"
			(at 0 0 270)
			(layer "F.Fab")
			(hide yes)
			(effects
				(font
					(size 1.27 1.27)
					(thickness 0.15)
				)
			)
		)
		(property "Author" "Antmicro"
			(at -23.425499 318.175501 0)
			(layer "B.Fab")
			(hide yes)
			(effects
				(font
					(size 1 1)
					(thickness 0.15)
				)
				(justify mirror)
			)
		)
		(property "Dielectric" "X5R"
			(at -23.425499 318.175501 0)
			(layer "B.Fab")
			(hide yes)
			(effects
				(font
					(size 1 1)
					(thickness 0.15)
				)
				(justify mirror)
			)
		)
		(property "License" "Apache-2.0"
			(at -23.425499 318.175501 0)
			(layer "B.Fab")
			(hide yes)
			(effects
				(font
					(size 1 1)
					(thickness 0.15)
				)
				(justify mirror)
			)
		)
		(property "MPN" "GRM155R61H104KE14D"
			(at -23.425499 318.175501 0)
			(layer "B.Fab")
			(hide yes)
			(effects
				(font
					(size 1 1)
					(thickness 0.15)
				)
				(justify mirror)
			)
		)
		(property "Manufacturer" "Murata"
			(at -23.425499 318.175501 0)
			(layer "B.Fab")
			(hide yes)
			(effects
				(font
					(size 1 1)
					(thickness 0.15)
				)
				(justify mirror)
			)
		)
		(property "Val" "100n"
			(at -23.425499 318.175501 0)
			(layer "B.Fab")
			(hide yes)
			(effects
				(font
					(size 1 1)
					(thickness 0.15)
				)
				(justify mirror)
			)
		)
		(property "Voltage" "50V"
			(at -23.425499 318.175501 0)
			(layer "B.Fab")
			(hide yes)
			(effects
				(font
					(size 1 1)
					(thickness 0.15)
				)
				(justify mirror)
			)
		)
		(sheetname "/FPGA power/")
		(sheetfile "fpga-power.kicad_sch")
		(attr smd)
		(fp_rect
			(start -0.9656 0.4572)
			(end 0.9652 -0.4828)
			(stroke
				(width 0.05)
				(type solid)
			)
			(fill no)
			(layer "B.CrtYd")
		)
		(fp_line
			(start -0.5 0.25)
			(end 0.498 0.25)
			(stroke
				(width 0.15)
				(type solid)
			)
			(layer "B.Fab")
		)
		(fp_line
			(start 0.498 0.25)
			(end 0.498 -0.248)
			(stroke
				(width 0.15)
				(type solid)
			)
			(layer "B.Fab")
		)
		(fp_line
			(start -0.5 -0.248)
			(end -0.5 0.25)
			(stroke
				(width 0.15)
				(type solid)
			)
			(layer "B.Fab")
		)
		(fp_line
			(start 0.498 -0.248)
			(end -0.5 -0.248)
			(stroke
				(width 0.15)
				(type solid)
			)
			(layer "B.Fab")
		)
		(pad "1" smd roundrect
			(at -0.5 0 180)
			(size 0.6 0.6)
			(layers "B.Cu" "B.Mask" "B.Paste")
			(roundrect_rratio 0.25)
			(net 1 "GND")
			(pintype "passive")
		)
		(pad "2" smd roundrect
			(at 0.498 0 270)
			(size 0.6 0.6)
			(layers "B.Cu" "B.Mask" "B.Paste")
			(roundrect_rratio 0.25)
			(net 200 "+3V3")
			(pintype "passive")
		)
	)
	(footprint "antmicro-footprints:C_0402_1005Metric"
		(layer "B.Cu")
		(at 141.525501 204.850501 90)
		(descr "Capacitor SMD 0402")
		(tags "capacitor SMD 0402")
		(property "Reference" "C231"
			(at 0 0.699 270)
			(layer "B.SilkS")
			(hide yes)
			(effects
				(font
					(size 0.7 0.7)
					(thickness 0.15)
				)
				(justify left bottom mirror)
			)
		)
		(property "Value" "C_100n_0402"
			(at -1.022927 -2.155213 270)
			(layer "B.Fab")
			(effects
				(font
					(size 0.7 0.7)
					(thickness 0.15)
				)
				(justify left bottom mirror)
			)
		)
		(property "Datasheet" "https://www.murata.com/products/productdetail?partno=GRM155R61H104KE14%23"
			(at 0 0 90)
			(layer "F.Fab")
			(hide yes)
			(effects
				(font
					(size 1.27 1.27)
					(thickness 0.15)
				)
			)
		)
		(property "Author" "Antmicro"
			(at 346.376002 63.325 0)
			(layer "B.Fab")
			(hide yes)
			(effects
				(font
					(size 1 1)
					(thickness 0.15)
				)
				(justify mirror)
			)
		)
		(property "Dielectric" "X5R"
			(at 346.376002 63.325 0)
			(layer "B.Fab")
			(hide yes)
			(effects
				(font
					(size 1 1)
					(thickness 0.15)
				)
				(justify mirror)
			)
		)
		(property "License" "Apache-2.0"
			(at 346.376002 63.325 0)
			(layer "B.Fab")
			(hide yes)
			(effects
				(font
					(size 1 1)
					(thickness 0.15)
				)
				(justify mirror)
			)
		)
		(property "MPN" "GRM155R61H104KE14D"
			(at 346.376002 63.325 0)
			(layer "B.Fab")
			(hide yes)
			(effects
				(font
					(size 1 1)
					(thickness 0.15)
				)
				(justify mirror)
			)
		)
		(property "Manufacturer" "Murata"
			(at 346.376002 63.325 0)
			(layer "B.Fab")
			(hide yes)
			(effects
				(font
					(size 1 1)
					(thickness 0.15)
				)
				(justify mirror)
			)
		)
		(property "Val" "100n"
			(at 346.376002 63.325 0)
			(layer "B.Fab")
			(hide yes)
			(effects
				(font
					(size 1 1)
					(thickness 0.15)
				)
				(justify mirror)
			)
		)
		(property "Voltage" "50V"
			(at 346.376002 63.325 0)
			(layer "B.Fab")
			(hide yes)
			(effects
				(font
					(size 1 1)
					(thickness 0.15)
				)
				(justify mirror)
			)
		)
		(sheetname "/FPGA MGT Interface/")
		(sheetfile "fpga-mgt.kicad_sch")
		(attr smd)
		(fp_rect
			(start -0.9659 0.481258)
			(end 0.9649 -0.458742)
			(stroke
				(width 0.05)
				(type solid)
			)
			(fill no)
			(layer "B.CrtYd")
		)
		(fp_line
			(start 0.499 -0.248)
			(end -0.499 -0.248)
			(stroke
				(width 0.15)
				(type solid)
			)
			(layer "B.Fab")
		)
		(fp_line
			(start -0.499 -0.248)
			(end -0.499 0.25)
			(stroke
				(width 0.15)
				(type solid)
			)
			(layer "B.Fab")
		)
		(fp_line
			(start 0.499 0.25)
			(end 0.499 -0.248)
			(stroke
				(width 0.15)
				(type solid)
			)
			(layer "B.Fab")
		)
		(fp_line
			(start -0.499 0.25)
			(end 0.499 0.25)
			(stroke
				(width 0.15)
				(type solid)
			)
			(layer "B.Fab")
		)
		(pad "1" smd roundrect
			(at -0.484 0 90)
			(size 0.59 0.64)
			(layers "B.Cu" "B.Mask" "B.Paste")
			(roundrect_rratio 0.25)
			(net 26 "/FPGA MGT Interface/PCIE.TXD2_N")
			(pintype "passive")
		)
		(pad "2" smd roundrect
			(at 0.484 0 90)
			(size 0.59 0.64)
			(layers "B.Cu" "B.Mask" "B.Paste")
			(roundrect_rratio 0.25)
			(net 27 "/FPGA MGT Interface/GTX_TX1_N")
			(pintype "passive")
		)
	)
	(footprint "antmicro-footprints:R_0402_1005Metric"
		(layer "B.Cu")
		(at 158.500501 175.276 180)
		(descr "Resistor SMD 0402")
		(tags "resistor SMD 0402")
		(property "Reference" "R170"
			(at -1.122484 0.772697 0)
			(layer "B.SilkS")
			(hide yes)
			(effects
				(font
					(size 0.7 0.7)
					(thickness 0.15)
				)
				(justify left bottom mirror)
			)
		)
		(property "Value" "R_10k_0402"
			(at -1.011843 -1.772047 0)
			(layer "B.Fab")
			(effects
				(font
					(size 0.7 0.7)
					(thickness 0.15)
				)
				(justify left bottom mirror)
			)
		)
		(property "Datasheet" "https://www.bourns.com/docs/product-datasheets/cr.pdf"
			(at 0 0 180)
			(layer "F.Fab")
			(hide yes)
			(effects
				(font
					(size 1.27 1.27)
					(thickness 0.15)
				)
			)
		)
		(property "Author" "Antmicro"
			(at 317.001002 350.552 0)
			(layer "B.Fab")
			(hide yes)
			(effects
				(font
					(size 1 1)
					(thickness 0.15)
				)
				(justify mirror)
			)
		)
		(property "License" "Apache-2.0"
			(at 317.001002 350.552 0)
			(layer "B.Fab")
			(hide yes)
			(effects
				(font
					(size 1 1)
					(thickness 0.15)
				)
				(justify mirror)
			)
		)
		(property "MPN" "CR0402-FX-1002GLF"
			(at 317.001002 350.552 0)
			(layer "B.Fab")
			(hide yes)
			(effects
				(font
					(size 1 1)
					(thickness 0.15)
				)
				(justify mirror)
			)
		)
		(property "Manufacturer" "Bourns"
			(at 317.001002 350.552 0)
			(layer "B.Fab")
			(hide yes)
			(effects
				(font
					(size 1 1)
					(thickness 0.15)
				)
				(justify mirror)
			)
		)
		(property "Tolerance" "1%"
			(at 317.001002 350.552 0)
			(layer "B.Fab")
			(hide yes)
			(effects
				(font
					(size 1 1)
					(thickness 0.15)
				)
				(justify mirror)
			)
		)
		(property "Val" "10k"
			(at 317.001002 350.552 0)
			(layer "B.Fab")
			(hide yes)
			(effects
				(font
					(size 1 1)
					(thickness 0.15)
				)
				(justify mirror)
			)
		)
		(sheetname "/Supply/")
		(sheetfile "supply.kicad_sch")
		(attr smd)
		(fp_rect
			(start -0.93 0.47)
			(end 0.93 -0.47)
			(stroke
				(width 0.05)
				(type solid)
			)
			(fill no)
			(layer "B.CrtYd")
		)
		(fp_rect
			(start -0.5 0.25)
			(end 0.5 -0.25)
			(stroke
				(width 0.15)
				(type solid)
			)
			(fill no)
			(layer "B.Fab")
		)
		(pad "1" smd roundrect
			(at -0.485 0 180)
			(size 0.59 0.64)
			(layers "B.Cu" "B.Mask" "B.Paste")
			(roundrect_rratio 0.25)
			(net 332 "Net-(J8-Pin_4)")
			(pintype "passive")
		)
		(pad "2" smd roundrect
			(at 0.485 0 180)
			(size 0.59 0.64)
			(layers "B.Cu" "B.Mask" "B.Paste")
			(roundrect_rratio 0.25)
			(net 201 "+5V")
			(pintype "passive")
		)
	)
	(footprint "antmicro-footprints:C_0402_1005Metric"
		(layer "B.Cu")
		(at 137.375001 179.8025 90)
		(descr "Capacitor SMD 0402 (1005 Metric), square (rectangular) end terminal, IPC_7351 nominal, (Body size source: IPC-SM-782 page 76, https://www.pcb-3d.com/wordpress/wp-content/uploads/ipc-sm-782a_amendment_1_and_2.pdf)")
		(tags "capacitor 0402")
		(property "Reference" "C55"
			(at 0 1.17 270)
			(layer "B.SilkS")
			(hide yes)
			(effects
				(font
					(size 0.7 0.7)
					(thickness 0.15)
				)
				(justify left bottom mirror)
			)
		)
		(property "Value" "C_100n_0402"
			(at 0 -1.169 270)
			(layer "B.Fab")
			(effects
				(font
					(size 0.7 0.7)
					(thickness 0.15)
				)
				(justify left bottom mirror)
			)
		)
		(property "Datasheet" "https://www.murata.com/products/productdetail?partno=GRM155R61H104KE14%23"
			(at 0 0 90)
			(layer "F.Fab")
			(hide yes)
			(effects
				(font
					(size 1.27 1.27)
					(thickness 0.15)
				)
			)
		)
		(property "Author" "Antmicro"
			(at 317.177501 42.427499 0)
			(layer "B.Fab")
			(hide yes)
			(effects
				(font
					(size 1 1)
					(thickness 0.15)
				)
				(justify mirror)
			)
		)
		(property "Dielectric" "X5R"
			(at 317.177501 42.427499 0)
			(layer "B.Fab")
			(hide yes)
			(effects
				(font
					(size 1 1)
					(thickness 0.15)
				)
				(justify mirror)
			)
		)
		(property "License" "Apache-2.0"
			(at 317.177501 42.427499 0)
			(layer "B.Fab")
			(hide yes)
			(effects
				(font
					(size 1 1)
					(thickness 0.15)
				)
				(justify mirror)
			)
		)
		(property "MPN" "GRM155R61H104KE14D"
			(at 317.177501 42.427499 0)
			(layer "B.Fab")
			(hide yes)
			(effects
				(font
					(size 1 1)
					(thickness 0.15)
				)
				(justify mirror)
			)
		)
		(property "Manufacturer" "Murata"
			(at 317.177501 42.427499 0)
			(layer "B.Fab")
			(hide yes)
			(effects
				(font
					(size 1 1)
					(thickness 0.15)
				)
				(justify mirror)
			)
		)
		(property "Val" "100n"
			(at 317.177501 42.427499 0)
			(layer "B.Fab")
			(hide yes)
			(effects
				(font
					(size 1 1)
					(thickness 0.15)
				)
				(justify mirror)
			)
		)
		(property "Voltage" "50V"
			(at 317.177501 42.427499 0)
			(layer "B.Fab")
			(hide yes)
			(effects
				(font
					(size 1 1)
					(thickness 0.15)
				)
				(justify mirror)
			)
		)
		(sheetname "/FPGA power/")
		(sheetfile "fpga-power.kicad_sch")
		(attr smd)
		(fp_rect
			(start -0.9656 0.4572)
			(end 0.9652 -0.4828)
			(stroke
				(width 0.05)
				(type solid)
			)
			(fill no)
			(layer "B.CrtYd")
		)
		(fp_line
			(start 0.498 -0.248)
			(end -0.5 -0.248)
			(stroke
				(width 0.15)
				(type solid)
			)
			(layer "B.Fab")
		)
		(fp_line
			(start -0.5 -0.248)
			(end -0.5 0.25)
			(stroke
				(width 0.15)
				(type solid)
			)
			(layer "B.Fab")
		)
		(fp_line
			(start 0.498 0.25)
			(end 0.498 -0.248)
			(stroke
				(width 0.15)
				(type solid)
			)
			(layer "B.Fab")
		)
		(fp_line
			(start -0.5 0.25)
			(end 0.498 0.25)
			(stroke
				(width 0.15)
				(type solid)
			)
			(layer "B.Fab")
		)
		(pad "1" smd roundrect
			(at -0.5 0)
			(size 0.6 0.6)
			(layers "B.Cu" "B.Mask" "B.Paste")
			(roundrect_rratio 0.25)
			(net 1 "GND")
			(pintype "passive")
		)
		(pad "2" smd roundrect
			(at 0.498 0 90)
			(size 0.6 0.6)
			(layers "B.Cu" "B.Mask" "B.Paste")
			(roundrect_rratio 0.25)
			(net 227 "+1V0")
			(pintype "passive")
		)
	)
	(footprint "antmicro-footprints:R_0402_1005Metric"
		(layer "B.Cu")
		(at 202.875 164.85 90)
		(descr "Resistor SMD 0402")
		(tags "resistor SMD 0402")
		(property "Reference" "R167"
			(at 3.85 0.375 270)
			(layer "B.SilkS")
			(effects
				(font
					(size 0.7 0.7)
					(thickness 0.15)
				)
				(justify left bottom mirror)
			)
		)
		(property "Value" "R_0R_0402"
			(at -1.011843 -1.772047 270)
			(layer "B.Fab")
			(effects
				(font
					(size 0.7 0.7)
					(thickness 0.15)
				)
				(justify left bottom mirror)
			)
		)
		(property "Datasheet" "https://industrial.panasonic.com/cdbs/www-data/pdf/RDA0000/AOA0000C301.pdf"
			(at 0 0 90)
			(layer "F.Fab")
			(hide yes)
			(effects
				(font
					(size 1.27 1.27)
					(thickness 0.15)
				)
			)
		)
		(property "Author" "Antmicro"
			(at 367.725 -38.025 0)
			(layer "B.Fab")
			(hide yes)
			(effects
				(font
					(size 1 1)
					(thickness 0.15)
				)
				(justify mirror)
			)
		)
		(property "Current" "1A"
			(at 367.725 -38.025 0)
			(layer "B.Fab")
			(hide yes)
			(effects
				(font
					(size 1 1)
					(thickness 0.15)
				)
				(justify mirror)
			)
		)
		(property "License" "Apache-2.0"
			(at 367.725 -38.025 0)
			(layer "B.Fab")
			(hide yes)
			(effects
				(font
					(size 1 1)
					(thickness 0.15)
				)
				(justify mirror)
			)
		)
		(property "MPN" "ERJ2GE0R00X"
			(at 367.725 -38.025 0)
			(layer "B.Fab")
			(hide yes)
			(effects
				(font
					(size 1 1)
					(thickness 0.15)
				)
				(justify mirror)
			)
		)
		(property "Manufacturer" "Panasonic"
			(at 367.725 -38.025 0)
			(layer "B.Fab")
			(hide yes)
			(effects
				(font
					(size 1 1)
					(thickness 0.15)
				)
				(justify mirror)
			)
		)
		(property "Tolerance" ""
			(at 367.725 -38.025 0)
			(layer "B.Fab")
			(hide yes)
			(effects
				(font
					(size 1 1)
					(thickness 0.15)
				)
				(justify mirror)
			)
		)
		(property "Val" "0R"
			(at 367.725 -38.025 0)
			(layer "B.Fab")
			(hide yes)
			(effects
				(font
					(size 1 1)
					(thickness 0.15)
				)
				(justify mirror)
			)
		)
		(sheetname "/Supply/")
		(sheetfile "supply.kicad_sch")
		(attr exclude_from_pos_files exclude_from_bom dnp)
		(fp_rect
			(start -0.93 0.47)
			(end 0.93 -0.47)
			(stroke
				(width 0.05)
				(type solid)
			)
			(fill no)
			(layer "B.CrtYd")
		)
		(fp_rect
			(start -0.5 0.25)
			(end 0.5 -0.25)
			(stroke
				(width 0.15)
				(type solid)
			)
			(fill no)
			(layer "B.Fab")
		)
		(pad "1" smd roundrect
			(at -0.485 0 90)
			(size 0.59 0.64)
			(layers "B.Cu" "B.Mask" "B.Paste")
			(roundrect_rratio 0.25)
			(net 1 "GND")
			(pintype "passive")
		)
		(pad "2" smd roundrect
			(at 0.485 0 90)
			(size 0.59 0.64)
			(layers "B.Cu" "B.Mask" "B.Paste")
			(roundrect_rratio 0.25)
			(net 217 "/Supply/FB7")
			(pintype "passive")
		)
	)
	(footprint "antmicro-footprints:R_0402_1005Metric"
		(layer "B.Cu")
		(at 143.4 142.4 90)
		(descr "Resistor SMD 0402")
		(tags "resistor SMD 0402")
		(property "Reference" "R35"
			(at 3 0.3 270)
			(layer "B.SilkS")
			(effects
				(font
					(size 0.7 0.7)
					(thickness 0.15)
				)
				(justify left bottom mirror)
			)
		)
		(property "Value" "R_0R_0402"
			(at -1.011843 -1.772047 270)
			(layer "B.Fab")
			(effects
				(font
					(size 0.7 0.7)
					(thickness 0.15)
				)
				(justify left bottom mirror)
			)
		)
		(property "Datasheet" "https://industrial.panasonic.com/cdbs/www-data/pdf/RDA0000/AOA0000C301.pdf"
			(at 0 0 90)
			(layer "F.Fab")
			(hide yes)
			(effects
				(font
					(size 1.27 1.27)
					(thickness 0.15)
				)
			)
		)
		(property "Author" "Antmicro"
			(at 285.8 -1 0)
			(layer "B.Fab")
			(hide yes)
			(effects
				(font
					(size 1 1)
					(thickness 0.15)
				)
				(justify mirror)
			)
		)
		(property "Current" "1A"
			(at 285.8 -1 0)
			(layer "B.Fab")
			(hide yes)
			(effects
				(font
					(size 1 1)
					(thickness 0.15)
				)
				(justify mirror)
			)
		)
		(property "License" "Apache-2.0"
			(at 285.8 -1 0)
			(layer "B.Fab")
			(hide yes)
			(effects
				(font
					(size 1 1)
					(thickness 0.15)
				)
				(justify mirror)
			)
		)
		(property "MPN" "ERJ2GE0R00X"
			(at 285.8 -1 0)
			(layer "B.Fab")
			(hide yes)
			(effects
				(font
					(size 1 1)
					(thickness 0.15)
				)
				(justify mirror)
			)
		)
		(property "Manufacturer" "Panasonic"
			(at 285.8 -1 0)
			(layer "B.Fab")
			(hide yes)
			(effects
				(font
					(size 1 1)
					(thickness 0.15)
				)
				(justify mirror)
			)
		)
		(property "Tolerance" ""
			(at 285.8 -1 0)
			(layer "B.Fab")
			(hide yes)
			(effects
				(font
					(size 1 1)
					(thickness 0.15)
				)
				(justify mirror)
			)
		)
		(property "Val" "0R"
			(at 285.8 -1 0)
			(layer "B.Fab")
			(hide yes)
			(effects
				(font
					(size 1 1)
					(thickness 0.15)
				)
				(justify mirror)
			)
		)
		(sheetname "/DDR5 SODIMM/")
		(sheetfile "ddr5-sodimm.kicad_sch")
		(attr exclude_from_pos_files exclude_from_bom dnp)
		(fp_rect
			(start -0.93 0.47)
			(end 0.93 -0.47)
			(stroke
				(width 0.05)
				(type solid)
			)
			(fill no)
			(layer "B.CrtYd")
		)
		(fp_rect
			(start -0.5 0.25)
			(end 0.5 -0.25)
			(stroke
				(width 0.15)
				(type solid)
			)
			(fill no)
			(layer "B.Fab")
		)
		(pad "1" smd roundrect
			(at -0.485 0 90)
			(size 0.59 0.64)
			(layers "B.Cu" "B.Mask" "B.Paste")
			(roundrect_rratio 0.25)
			(net 173 "/DDR5 SODIMM/RFU3")
			(pintype "passive")
		)
		(pad "2" smd roundrect
			(at 0.485 0 90)
			(size 0.59 0.64)
			(layers "B.Cu" "B.Mask" "B.Paste")
			(roundrect_rratio 0.25)
			(net 274 "RFU_3")
			(pintype "passive")
		)
	)
)
